# BASEBOARD_FAB2 (Tioga Pass) — schematic netlist excerpt (pin names and nets, part order shuffled) for the footprints in the layout excerpt that follows; sources: Cadence DE-HDL packaged netlist, KiCad conversion of Wiwynn_Tioga_Pass_MB.brd

J6U1  SCONN288_H44441003  SCONN  pkg PIP  page 46
  \12v\(1)  = P12V_NVDIMM_ABC
  VSS(93)  = GND
  DQ(4)  = M_B_DQ<4>
  VSS(92)  = GND
  DQ(0)  = M_B_DQ<0>
  VSS(91)  = GND
  DQS9P  = M_B_DQS_DP<9>
  DQS9N  = M_B_DQS_DN<9>
  VSS(90)  = GND
  DQ(6)  = M_B_DQ<6>
  VSS(89)  = GND
  DQ(2)  = M_B_DQ<2>
  VSS(88)  = GND
  DQ(12)  = M_B_DQ<12>
  VSS(87)  = GND
  DQ(8)  = M_B_DQ<8>
  VSS(86)  = GND
  DQS10P  = M_B_DQS_DP<10>
  DQS10N  = M_B_DQS_DN<10>
  VSS(85)  = GND
  DQ(14)  = M_B_DQ<14>
  VSS(84)  = GND
  DQ(10)  = M_B_DQ<10>
  VSS(83)  = GND
  DQ(20)  = M_B_DQ<20>
  VSS(82)  = GND
  DQ(16)  = M_B_DQ<16>
  VSS(81)  = GND
  DQS11P  = M_B_DQS_DP<11>
  DQS11N  = M_B_DQS_DN<11>
  VSS(80)  = GND
  DQ(22)  = M_B_DQ<22>
  VSS(79)  = GND
  DQ(18)  = M_B_DQ<18>
  VSS(78)  = GND
  DQ(28)  = M_B_DQ<28>
  VSS(77)  = GND
  DQ(24)  = M_B_DQ<24>
  VSS(76)  = GND
  DQS12P  = M_B_DQS_DP<12>
  DQS12N  = M_B_DQS_DN<12>
  VSS(75)  = GND
  DQ(30)  = M_B_DQ<30>
  VSS(74)  = GND
  DQ(26)  = M_B_DQ<26>
  VSS(73)  = GND
  CB(4)  = M_B_ECC<4>
  VSS(72)  = GND
  CB(0)  = M_B_ECC<0>
  VSS(71)  = GND
  DQS17P  = M_B_DQS_DP<17>
  DQS17N  = M_B_DQS_DN<17>
  VSS(70)  = GND
  CB(6)  = M_B_ECC<6>
  VSS(69)  = GND
  CB(2)  = M_B_ECC<2>
  VSS(68)  = GND
  RESET_N  = M_ABC_RST_N
  VDD(25)  = PVDDQ_ABC
  CKE(0)  = M_B_CKE<2>
  VDD(24)  = PVDDQ_ABC
  ACT_N  = M_B_ACT_N
  BG(0)  = M_B_BG<0>
  VDD(23)  = PVDDQ_ABC
  A12  = M_B_MA<12>
  A9  = M_B_MA<9>
  VDD(22)  = PVDDQ_ABC
  A8  = M_B_MA<8>
  A6  = M_B_MA<6>
  VDD(21)  = PVDDQ_ABC
  A3  = M_B_MA<3>
  A1  = M_B_MA<1>
  VDD(20)  = PVDDQ_ABC
  CK0P  = M_B_CLK_DP<2>
  CK0N  = M_B_CLK_DN<2>
  VDD(19)  = PVDDQ_ABC
  VTT(1)  = PVTT_ABC
  EVENT_N  = FM_DIMM_EVENT_COD_N
  A0  = M_B_MA<0>
  VDD(18)  = PVDDQ_ABC
  BA(0)  = M_B_BA<0>
  A16_RAS_N  = M_B_MA<16>
  VDD(17)  = PVDDQ_ABC
  S0_N  = M_B_CS_N<4>
  VDD(16)  = PVDDQ_ABC
  A15_CAS_N  = M_B_MA<15>
  ODT(0)  = M_B_ODT<2>
  VDD(15)  = PVDDQ_ABC
  S1_N  = M_B_CS_N<5>
  VDD(14)  = PVDDQ_ABC
  ODT(1)  = M_B_ODT<3>
  VDD(13)  = PVDDQ_ABC
  S2_N_C(0)  = M_B_CS_N<6>
  VSS(67)  = GND
  DQ(36)  = M_B_DQ<36>
  VSS(66)  = GND
  DQ(32)  = M_B_DQ<32>
  VSS(65)  = GND
  DQS13P  = M_B_DQS_DP<13>
  DQS13N  = M_B_DQS_DN<13>
  VSS(64)  = GND
  DQ(38)  = M_B_DQ<38>
  VSS(63)  = GND
  DQ(34)  = M_B_DQ<34>
  VSS(62)  = GND
  DQ(44)  = M_B_DQ<44>
  VSS(61)  = GND
  DQ(40)  = M_B_DQ<40>
  VSS(60)  = GND
  DQS14P  = M_B_DQS_DP<14>
  DQS14N  = M_B_DQS_DN<14>
  VSS(59)  = GND
  DQ(46)  = M_B_DQ<46>
  VSS(58)  = GND
  DQ(42)  = M_B_DQ<42>
  VSS(57)  = GND
  DQ(52)  = M_B_DQ<52>
  VSS(56)  = GND
  DQ(48)  = M_B_DQ<48>
  VSS(55)  = GND
  DQS15P  = M_B_DQS_DP<15>
  DQS15N  = M_B_DQS_DN<15>
  VSS(54)  = GND
  DQ(54)  = M_B_DQ<54>
  VSS(53)  = GND
  DQ(50)  = M_B_DQ<50>
  VSS(52)  = GND
  DQ(60)  = M_B_DQ<60>
  VSS(51)  = GND
  DQ(56)  = M_B_DQ<56>
  VSS(50)  = GND
  DQS16P  = M_B_DQS_DP<16>
  DQS16N  = M_B_DQS_DN<16>
  VSS(49)  = GND
  DQ(62)  = M_B_DQ<62>
  VSS(48)  = GND
  DQ(58)  = M_B_DQ<58>
  VSS(47)  = GND
  SA(0)  = PVPP_ABC
  SA(1)  = PVPP_ABC
  SCL  = SMB_DDR_ABC_VPP_SCL
  VPP(4)  = PVPP_ABC
  VPP(3)  = PVPP_ABC
  RFU(2)  = TP_CH_B_DIMM_B1_RFU_2
  \12v\(0)  = P12V_NVDIMM_ABC
  VREFCA  = M_B_VREF
  VSS(46)  = GND
  DQ(5)  = M_B_DQ<5>
  VSS(45)  = GND
  DQ(1)  = M_B_DQ<1>
  VSS(44)  = GND
  DQS0N  = M_B_DQS_DN<0>
  DQS0P  = M_B_DQS_DP<0>
  VSS(43)  = GND
  DQ(7)  = M_B_DQ<7>
  VSS(42)  = GND
  DQ(3)  = M_B_DQ<3>
  VSS(41)  = GND
  DQ(13)  = M_B_DQ<13>
  VSS(40)  = GND
  DQ(9)  = M_B_DQ<9>
  VSS(39)  = GND
  DQS1N  = M_B_DQS_DN<1>
  DQS1P  = M_B_DQS_DP<1>
  VSS(38)  = GND
  DQ(15)  = M_B_DQ<15>
  VSS(37)  = GND
  DQ(11)  = M_B_DQ<11>
  VSS(36)  = GND
  DQ(21)  = M_B_DQ<21>
  VSS(35)  = GND
  DQ(17)  = M_B_DQ<17>
  VSS(34)  = GND
  DQS2N  = M_B_DQS_DN<2>
  DQS2P  = M_B_DQS_DP<2>
  VSS(33)  = GND
  DQ(23)  = M_B_DQ<23>
  VSS(32)  = GND
  DQ(19)  = M_B_DQ<19>
  VSS(31)  = GND
  DQ(29)  = M_B_DQ<29>
  VSS(30)  = GND
  DQ(25)  = M_B_DQ<25>
  VSS(29)  = GND
  DQS3N  = M_B_DQS_DN<3>
  DQS3P  = M_B_DQS_DP<3>
  VSS(28)  = GND
  DQ(31)  = M_B_DQ<31>
  VSS(27)  = GND
  DQ(27)  = M_B_DQ<27>
  VSS(26)  = GND
  CB(5)  = M_B_ECC<5>
  VSS(25)  = GND
  CB(1)  = M_B_ECC<1>
  VSS(24)  = GND
  DQS8N  = M_B_DQS_DN<8>
  DQS8P  = M_B_DQS_DP<8>
  VSS(23)  = GND
  CB(7)  = M_B_ECC<7>
  VSS(22)  = GND
  CB(3)  = M_B_ECC<3>
  VSS(21)  = GND
  CKE(1)  = M_B_CKE<3>
  VDD(12)  = PVDDQ_ABC
  RFU(0)  = TP_CH_B_DIMM_B1_RFU_0
  VDD(11)  = PVDDQ_ABC
  BG(1)  = M_B_BG<1>
  ALERT_N  = M_B_ALERT_N
  VDD(10)  = PVDDQ_ABC
  A11  = M_B_MA<11>
  A7  = M_B_MA<7>
  VDD(9)  = PVDDQ_ABC
  A5  = M_B_MA<5>
  A4  = M_B_MA<4>
  VDD(8)  = PVDDQ_ABC
  A2  = M_B_MA<2>
  VDD(7)  = PVDDQ_ABC
  CK1P  = M_B_CLK_DP<3>
  CK1N  = M_B_CLK_DN<3>
  VDD(6)  = PVDDQ_ABC
  VTT(0)  = PVTT_ABC
  PAR  = M_B_PAR
  VDD(5)  = PVDDQ_ABC
  BA(1)  = M_B_BA<1>
  A10  = M_B_MA<10>
  VDD(4)  = PVDDQ_ABC
  RFU(1)  = TP_CH_B_DIMM_B1_RFU_1
  A14_WE_N  = M_B_MA<14>
  VDD(3)  = PVDDQ_ABC
  SAVE_N_NC  = FM_ADR_COMPLETE_ABC_N
  VDD(2)  = PVDDQ_ABC
  A13  = M_B_MA<13>
  VDD(1)  = PVDDQ_ABC
  A17  = M_B_MA<17>
  C(2)  = M_B_C<2>
  VDD(0)  = PVDDQ_ABC
  S3_N_C(1)  = M_B_CS_N<7>
  SA(2)  = GND
  VSS(20)  = GND
  DQ(37)  = M_B_DQ<37>
  VSS(19)  = GND
  DQ(33)  = M_B_DQ<33>
  VSS(18)  = GND
  DQS4N  = M_B_DQS_DN<4>
  DQS4P  = M_B_DQS_DP<4>
  VSS(17)  = GND
  DQ(39)  = M_B_DQ<39>
  VSS(16)  = GND
  DQ(35)  = M_B_DQ<35>
  VSS(15)  = GND
  DQ(45)  = M_B_DQ<45>
  VSS(14)  = GND
  DQ(41)  = M_B_DQ<41>
  VSS(13)  = GND
  DQS5N  = M_B_DQS_DN<5>
  DQS5P  = M_B_DQS_DP<5>
  VSS(12)  = GND
  DQ(47)  = M_B_DQ<47>
  VSS(11)  = GND
  DQ(43)  = M_B_DQ<43>
  VSS(10)  = GND
  DQ(53)  = M_B_DQ<53>
  VSS(9)  = GND
  DQ(49)  = M_B_DQ<49>
  VSS(8)  = GND
  DQS6N  = M_B_DQS_DN<6>
  DQS6P  = M_B_DQS_DP<6>
  VSS(7)  = GND
  DQ(55)  = M_B_DQ<55>
  VSS(6)  = GND
  DQ(51)  = M_B_DQ<51>
  VSS(5)  = GND
  DQ(61)  = M_B_DQ<61>
  VSS(4)  = GND
  DQ(57)  = M_B_DQ<57>
  VSS(3)  = GND
  DQS7N  = M_B_DQS_DN<7>
  DQS7P  = M_B_DQS_DP<7>
  VSS(2)  = GND
  DQ(63)  = M_B_DQ<63>
  VSS(1)  = GND
  DQ(59)  = M_B_DQ<59>
  VSS(0)  = GND
  VDDSPD  = PVPP_ABC
  SDA  = SMB_DDR_ABC_VPP_SDA
  VPP(1)  = PVPP_ABC
  VPP(0)  = PVPP_ABC
  VPP(2)  = PVPP_ABC

(kicad_pcb
	(version 20260206)
	(generator "pcbnew")
	(generator_version "10.0")
	(general
		(thickness 1.6)
		(legacy_teardrops no)
	)
	(paper "A4")
	(title_block
		(title "Wiwynn_Tioga_Pass_MB.brd")
		(comment 1 "Tioga Pass / footprint 2988 of 4770 (J6U1), pads 1-50 of 291")
	)
	(layers
		(0 "F.Cu" signal "TOP")
		(4 "In1.Cu" signal "L2GND")
		(6 "In2.Cu" signal "L3")
		(8 "In3.Cu" signal "L4GND")
		(10 "In4.Cu" signal "L5")
		(12 "In5.Cu" signal "L6GND")
		(14 "In6.Cu" signal "L7VCC")
		(16 "In7.Cu" signal "L8VCC")
		(18 "In8.Cu" signal "L9GND")
		(20 "In9.Cu" signal "L10")
		(22 "In10.Cu" signal "L11GND")
		(24 "In11.Cu" signal "L12")
		(26 "In12.Cu" signal "L13GND")
		(2 "B.Cu" signal "BOTTOM")
		(9 "F.Adhes" user "F.Adhesive")
		(11 "B.Adhes" user "B.Adhesive")
		(13 "F.Paste" user "Package Geometry/Pastemask Top")
		(15 "B.Paste" user "Package Geometry/Pastemask Bottom")
		(5 "F.SilkS" user "Ref Des/Silkscreen Top")
		(7 "B.SilkS" user "Ref Des/Silkscreen Bottom")
		(1 "F.Mask" user "Board Geometry/Soldermask Top")
		(3 "B.Mask" user "Board Geometry/Soldermask Bottom")
		(17 "Dwgs.User" user "User.Drawings")
		(19 "Cmts.User" user "User.Comments")
		(21 "Eco1.User" user "User.Eco1")
		(23 "Eco2.User" user "User.Eco2")
		(25 "Edge.Cuts" user "Board Geometry/Outline")
		(27 "Margin" user)
		(31 "F.CrtYd" user "Package Geometry/Place Bound Top")
		(29 "B.CrtYd" user "Package Geometry/Place Bound Bottom")
		(35 "F.Fab" user "Ref Des/Assembly Top")
		(33 "B.Fab" user "Ref Des/Assembly Bottom")
	)
	(footprint ""
		(layer "B.Cu")
		(at 194.700398 -15.222982 90)
		(property "Reference" "J6U1"
			(at 2.530348 39.10711 0)
			(unlocked yes)
			(layer "B.SilkS")
			(effects
				(font
					(size 0.7874 0.5842)
					(thickness 0.1524)
				)
				(justify left mirror)
			)
		)
		(property "Value" ""
			(at 0 0 90)
			(layer "B.Fab")
			(effects
				(font
					(size 1.27 1.27)
				)
				(justify mirror)
			)
		)
		(duplicate_pad_numbers_are_jumpers no)
		(pad "" thru_hole circle
			(at -2.29997 -5.649976 270)
			(size 2.8194 2.8194)
			(drill 2.4384)
			(layers "*.Cu" "*.Mask")
			(remove_unused_layers no)
			(clearance 0.127)
			(thermal_gap 0.127)
		)
		(pad "" thru_hole oval
			(at -2.29997 68.90004 270)
			(size 2.8194 1.5748)
			(drill oval 2.4384 1.1938)
			(layers "*.Cu" "*.Mask")
			(remove_unused_layers no)
			(clearance 0.127)
			(thermal_gap 0.127)
		)
		(pad "" thru_hole circle
			(at -2.29997 132.299964 270)
			(size 2.8194 2.8194)
			(drill 2.4384)
			(layers "*.Cu" "*.Mask")
			(remove_unused_layers no)
			(clearance 0.127)
			(thermal_gap 0.127)
		)
		(pad "1" smd rect
			(at 0 0 270)
			(size 1.8034 0.508)
			(layers "B.Cu" "B.Mask" "B.Paste")
			(net "P12V_NVDIMM_ABC")
		)
		(pad "2" smd rect
			(at 0 0.849884 270)
			(size 1.8034 0.508)
			(layers "B.Cu" "B.Mask" "B.Paste")
			(net "GND")
		)
		(pad "3" smd rect
			(at 0 1.700022 270)
			(size 1.8034 0.508)
			(layers "B.Cu" "B.Mask" "B.Paste")
			(net "M_B_DQ<4>")
		)
		(pad "4" smd rect
			(at 0 2.549906 270)
			(size 1.8034 0.508)
			(layers "B.Cu" "B.Mask" "B.Paste")
			(net "GND")
		)
		(pad "5" smd rect
			(at 0 3.400044 270)
			(size 1.8034 0.508)
			(layers "B.Cu" "B.Mask" "B.Paste")
			(net "M_B_DQ<0>")
		)
		(pad "6" smd rect
			(at 0 4.249928 270)
			(size 1.8034 0.508)
			(layers "B.Cu" "B.Mask" "B.Paste")
			(net "GND")
		)
		(pad "7" smd rect
			(at 0 5.100066 270)
			(size 1.8034 0.508)
			(layers "B.Cu" "B.Mask" "B.Paste")
			(net "M_B_DQS_DP<9>")
		)
		(pad "8" smd rect
			(at 0 5.94995 270)
			(size 1.8034 0.508)
			(layers "B.Cu" "B.Mask" "B.Paste")
			(net "M_B_DQS_DN<9>")
		)
		(pad "9" smd rect
			(at 0 6.800088 270)
			(size 1.8034 0.508)
			(layers "B.Cu" "B.Mask" "B.Paste")
			(net "GND")
		)
		(pad "10" smd rect
			(at 0 7.649972 270)
			(size 1.8034 0.508)
			(layers "B.Cu" "B.Mask" "B.Paste")
			(net "M_B_DQ<6>")
		)
		(pad "11" smd rect
			(at 0 8.50011 270)
			(size 1.8034 0.508)
			(layers "B.Cu" "B.Mask" "B.Paste")
			(net "GND")
		)
		(pad "12" smd rect
			(at 0 9.349994 270)
			(size 1.8034 0.508)
			(layers "B.Cu" "B.Mask" "B.Paste")
			(net "M_B_DQ<2>")
		)
		(pad "13" smd rect
			(at 0 10.199878 270)
			(size 1.8034 0.508)
			(layers "B.Cu" "B.Mask" "B.Paste")
			(net "GND")
		)
		(pad "14" smd rect
			(at 0 11.050016 270)
			(size 1.8034 0.508)
			(layers "B.Cu" "B.Mask" "B.Paste")
			(net "M_B_DQ<12>")
		)
		(pad "15" smd rect
			(at 0 11.8999 270)
			(size 1.8034 0.508)
			(layers "B.Cu" "B.Mask" "B.Paste")
			(net "GND")
		)
		(pad "16" smd rect
			(at 0 12.750038 270)
			(size 1.8034 0.508)
			(layers "B.Cu" "B.Mask" "B.Paste")
			(net "M_B_DQ<8>")
		)
		(pad "17" smd rect
			(at 0 13.599922 270)
			(size 1.8034 0.508)
			(layers "B.Cu" "B.Mask" "B.Paste")
			(net "GND")
		)
		(pad "18" smd rect
			(at 0 14.45006 270)
			(size 1.8034 0.508)
			(layers "B.Cu" "B.Mask" "B.Paste")
			(net "M_B_DQS_DP<10>")
		)
		(pad "19" smd rect
			(at 0 15.299944 270)
			(size 1.8034 0.508)
			(layers "B.Cu" "B.Mask" "B.Paste")
			(net "M_B_DQS_DN<10>")
		)
		(pad "20" smd rect
			(at 0 16.150082 270)
			(size 1.8034 0.508)
			(layers "B.Cu" "B.Mask" "B.Paste")
			(net "GND")
		)
		(pad "21" smd rect
			(at 0 16.999966 270)
			(size 1.8034 0.508)
			(layers "B.Cu" "B.Mask" "B.Paste")
			(net "M_B_DQ<14>")
		)
		(pad "22" smd rect
			(at 0 17.850104 270)
			(size 1.8034 0.508)
			(layers "B.Cu" "B.Mask" "B.Paste")
			(net "GND")
		)
		(pad "23" smd rect
			(at 0 18.699988 270)
			(size 1.8034 0.508)
			(layers "B.Cu" "B.Mask" "B.Paste")
			(net "M_B_DQ<10>")
		)
		(pad "24" smd rect
			(at 0 19.550126 270)
			(size 1.8034 0.508)
			(layers "B.Cu" "B.Mask" "B.Paste")
			(net "GND")
		)
		(pad "25" smd rect
			(at 0 20.40001 270)
			(size 1.8034 0.508)
			(layers "B.Cu" "B.Mask" "B.Paste")
			(net "M_B_DQ<20>")
		)
		(pad "26" smd rect
			(at 0 21.249894 270)
			(size 1.8034 0.508)
			(layers "B.Cu" "B.Mask" "B.Paste")
			(net "GND")
		)
		(pad "27" smd rect
			(at 0 22.100032 270)
			(size 1.8034 0.508)
			(layers "B.Cu" "B.Mask" "B.Paste")
			(net "M_B_DQ<16>")
		)
		(pad "28" smd rect
			(at 0 22.949916 270)
			(size 1.8034 0.508)
			(layers "B.Cu" "B.Mask" "B.Paste")
			(net "GND")
		)
		(pad "29" smd rect
			(at 0 23.800054 270)
			(size 1.8034 0.508)
			(layers "B.Cu" "B.Mask" "B.Paste")
			(net "M_B_DQS_DP<11>")
		)
		(pad "30" smd rect
			(at 0 24.649938 270)
			(size 1.8034 0.508)
			(layers "B.Cu" "B.Mask" "B.Paste")
			(net "M_B_DQS_DN<11>")
		)
		(pad "31" smd rect
			(at 0 25.500076 270)
			(size 1.8034 0.508)
			(layers "B.Cu" "B.Mask" "B.Paste")
			(net "GND")
		)
		(pad "32" smd rect
			(at 0 26.34996 270)
			(size 1.8034 0.508)
			(layers "B.Cu" "B.Mask" "B.Paste")
			(net "M_B_DQ<22>")
		)
		(pad "33" smd rect
			(at 0 27.200098 270)
			(size 1.8034 0.508)
			(layers "B.Cu" "B.Mask" "B.Paste")
			(net "GND")
		)
		(pad "34" smd rect
			(at 0 28.049982 270)
			(size 1.8034 0.508)
			(layers "B.Cu" "B.Mask" "B.Paste")
			(net "M_B_DQ<18>")
		)
		(pad "35" smd rect
			(at 0 28.90012 270)
			(size 1.8034 0.508)
			(layers "B.Cu" "B.Mask" "B.Paste")
			(net "GND")
		)
		(pad "36" smd rect
			(at 0 29.750004 270)
			(size 1.8034 0.508)
			(layers "B.Cu" "B.Mask" "B.Paste")
			(net "M_B_DQ<28>")
		)
		(pad "37" smd rect
			(at 0 30.599888 270)
			(size 1.8034 0.508)
			(layers "B.Cu" "B.Mask" "B.Paste")
			(net "GND")
		)
		(pad "38" smd rect
			(at 0 31.450026 270)
			(size 1.8034 0.508)
			(layers "B.Cu" "B.Mask" "B.Paste")
			(net "M_B_DQ<24>")
		)
		(pad "39" smd rect
			(at 0 32.29991 270)
			(size 1.8034 0.508)
			(layers "B.Cu" "B.Mask" "B.Paste")
			(net "GND")
		)
		(pad "40" smd rect
			(at 0 33.150048 270)
			(size 1.8034 0.508)
			(layers "B.Cu" "B.Mask" "B.Paste")
			(net "M_B_DQS_DP<12>")
		)
		(pad "41" smd rect
			(at 0 33.999932 270)
			(size 1.8034 0.508)
			(layers "B.Cu" "B.Mask" "B.Paste")
			(net "M_B_DQS_DN<12>")
		)
		(pad "42" smd rect
			(at 0 34.85007 270)
			(size 1.8034 0.508)
			(layers "B.Cu" "B.Mask" "B.Paste")
			(net "GND")
		)
		(pad "43" smd rect
			(at 0 35.699954 270)
			(size 1.8034 0.508)
			(layers "B.Cu" "B.Mask" "B.Paste")
			(net "M_B_DQ<30>")
		)
		(pad "44" smd rect
			(at 0 36.550092 270)
			(size 1.8034 0.508)
			(layers "B.Cu" "B.Mask" "B.Paste")
			(net "GND")
		)
		(pad "45" smd rect
			(at 0 37.399976 270)
			(size 1.8034 0.508)
			(layers "B.Cu" "B.Mask" "B.Paste")
			(net "M_B_DQ<26>")
		)
		(pad "46" smd rect
			(at 0 38.250114 270)
			(size 1.8034 0.508)
			(layers "B.Cu" "B.Mask" "B.Paste")
			(net "GND")
		)
		(pad "47" smd rect
			(at 0 39.099998 270)
			(size 1.8034 0.508)
			(layers "B.Cu" "B.Mask" "B.Paste")
			(net "M_B_ECC<4>")
		)
	)
)
